(kicad_pcb
	(version 20260206)
	(generator "pcbnew")
	(generator_version "10.0")
	(general
		(thickness 1.6)
		(legacy_teardrops no)
	)
	(paper "A4")
	(title_block
		(title "pdpb — Lightning_PDPB_BRD.brd")
		(comment 1 "Lightning (Wiwynn / Facebook NVMe JBOF) / footprints 1110-1116 of 1140")
	)
	(layers
		(0 "F.Cu" signal "TOP")
		(4 "In1.Cu" signal "L2GND")
		(6 "In2.Cu" signal "L3")
		(8 "In3.Cu" signal "L4VCC")
		(10 "In4.Cu" signal "L5VCC")
		(12 "In5.Cu" signal "L6")
		(14 "In6.Cu" signal "L7GND")
		(2 "B.Cu" signal "BOTTOM")
		(9 "F.Adhes" user "F.Adhesive")
		(11 "B.Adhes" user "B.Adhesive")
		(13 "F.Paste" user "Package Geometry/Pastemask Top")
		(15 "B.Paste" user "Package Geometry/Pastemask Bottom")
		(5 "F.SilkS" user "Ref Des/Silkscreen Top")
		(7 "B.SilkS" user "Ref Des/Silkscreen Bottom")
		(1 "F.Mask" user "Board Geometry/Soldermask Top")
		(3 "B.Mask" user "Board Geometry/Soldermask Bottom")
		(17 "Dwgs.User" user "User.Drawings")
		(19 "Cmts.User" user "User.Comments")
		(21 "Eco1.User" user "User.Eco1")
		(23 "Eco2.User" user "User.Eco2")
		(25 "Edge.Cuts" user "Board Geometry/Outline")
		(27 "Margin" user)
		(31 "F.CrtYd" user "Package Geometry/Place Bound Top")
		(29 "B.CrtYd" user "Package Geometry/Place Bound Bottom")
		(35 "F.Fab" user "Ref Des/Assembly Top")
		(33 "B.Fab" user "Ref Des/Assembly Bottom")
	)
	(footprint ""
		(layer "F.Cu")
		(at 197.799706 -498.959378 -90)
		(property "Reference" "Q23"
			(at 0 0 270)
			(layer "F.SilkS")
			(hide yes)
			(effects
				(font
					(size 1.27 1.27)
				)
			)
		)
		(property "Value" "2N7002A-7-GP"
			(at 0.127 -8.9662 270)
			(unlocked yes)
			(layer "F.Fab")
			(hide yes)
			(effects
				(font
					(size 1.016 1.016)
					(thickness 0.1524)
				)
			)
		)
		(property "Device Type" "SOT23DGS2D4H48"
			(at 0.127 -10.4902 270)
			(unlocked yes)
			(layer "F.Fab")
			(hide yes)
			(effects
				(font
					(size 1.016 1.016)
					(thickness 0.1524)
				)
			)
		)
		(duplicate_pad_numbers_are_jumpers no)
		(fp_line
			(start -1.651 1.778)
			(end 1.651 1.778)
			(stroke
				(width 0.1524)
				(type default)
			)
			(layer "F.SilkS")
		)
		(fp_line
			(start 1.651 1.778)
			(end 1.651 -1.778)
			(stroke
				(width 0.1524)
				(type default)
			)
			(layer "F.SilkS")
		)
		(fp_line
			(start -1.651 -1.778)
			(end -1.651 1.778)
			(stroke
				(width 0.1524)
				(type default)
			)
			(layer "F.SilkS")
		)
		(fp_line
			(start 1.651 -1.778)
			(end -1.651 -1.778)
			(stroke
				(width 0.1524)
				(type default)
			)
			(layer "F.SilkS")
		)
		(fp_poly
			(pts
				(xy -1.778 1.8796) (xy -1.778 -1.8796) (xy 1.778 -1.8796) (xy 1.778 1.8796)
			)
			(stroke
				(width 0)
				(type default)
			)
			(fill no)
			(layer "F.CrtYd")
		)
		(fp_poly
			(pts
				(xy -1.778 1.8796) (xy -1.778 -1.8796) (xy 1.778 -1.8796) (xy 1.778 1.8796)
			)
			(stroke
				(width 0)
				(type default)
			)
			(fill no)
			(layer "F.Fab")
		)
		(pad "D" smd custom
			(at 0 -0.9525 270)
			(size 0.1905 0.1905)
			(layers "F.Cu" "F.Mask" "F.Paste")
			(net "P12V_MOST0_GATE")
			(options
				(clearance outline)
				(anchor circle)
			)
			(primitives
				(gr_poly
					(pts
						(arc
							(start -0.1778 0.5715)
							(mid -0.321484 0.511984)
							(end -0.381 0.3683)
						)
						(arc
							(start -0.381 -0.3683)
							(mid -0.321484 -0.511984)
							(end -0.1778 -0.5715)
						)
						(arc
							(start 0.1778 -0.5715)
							(mid 0.321484 -0.511984)
							(end 0.381 -0.3683)
						)
						(arc
							(start 0.381 0.3683)
							(mid 0.321484 0.511984)
							(end 0.1778 0.5715)
						)
					)
					(width 0)
					(fill yes)
				)
			)
		)
		(pad "G" smd custom
			(at -0.98425 0.9525 270)
			(size 0.1905 0.1905)
			(layers "F.Cu" "F.Mask" "F.Paste")
			(net "SSD0_PWREN_R")
			(options
				(clearance outline)
				(anchor circle)
			)
			(primitives
				(gr_poly
					(pts
						(arc
							(start -0.1778 0.5715)
							(mid -0.321484 0.511984)
							(end -0.381 0.3683)
						)
						(arc
							(start -0.381 -0.3683)
							(mid -0.321484 -0.511984)
							(end -0.1778 -0.5715)
						)
						(arc
							(start 0.1778 -0.5715)
							(mid 0.321484 -0.511984)
							(end 0.381 -0.3683)
						)
						(arc
							(start 0.381 0.3683)
							(mid 0.321484 0.511984)
							(end 0.1778 0.5715)
						)
					)
					(width 0)
					(fill yes)
				)
			)
		)
		(pad "S" smd custom
			(at 0.98425 0.9525 270)
			(size 0.1905 0.1905)
			(layers "F.Cu" "F.Mask" "F.Paste")
			(net "GND")
			(options
				(clearance outline)
				(anchor circle)
			)
			(primitives
				(gr_poly
					(pts
						(arc
							(start -0.1778 0.5715)
							(mid -0.321484 0.511984)
							(end -0.381 0.3683)
						)
						(arc
							(start -0.381 -0.3683)
							(mid -0.321484 -0.511984)
							(end -0.1778 -0.5715)
						)
						(arc
							(start 0.1778 -0.5715)
							(mid 0.321484 -0.511984)
							(end 0.381 -0.3683)
						)
						(arc
							(start 0.381 0.3683)
							(mid 0.321484 0.511984)
							(end 0.1778 0.5715)
						)
					)
					(width 0)
					(fill yes)
				)
			)
		)
	)
	(footprint ""
		(layer "F.Cu")
		(at 36.957 -400.431 180)
		(property "Reference" "PC1240"
			(at 0 0 180)
			(layer "F.SilkS")
			(hide yes)
			(effects
				(font
					(size 1.27 1.27)
				)
			)
		)
		(property "Value" "SC22U25V6KX-GP-U"
			(at -2.860802 -5.279644 180)
			(unlocked yes)
			(layer "F.Fab")
			(hide yes)
			(effects
				(font
					(size 1.016 1.016)
					(thickness 0.1524)
				)
			)
		)
		(property "Device Type" "C1206-TO0D3H75"
			(at -2.860802 -6.803644 180)
			(unlocked yes)
			(layer "F.Fab")
			(hide yes)
			(effects
				(font
					(size 1.016 1.016)
					(thickness 0.1524)
				)
			)
		)
		(duplicate_pad_numbers_are_jumpers no)
		(fp_line
			(start 1.3081 2.3749)
			(end -1.3081 2.3749)
			(stroke
				(width 0.1524)
				(type default)
			)
			(layer "F.SilkS")
		)
		(fp_line
			(start 1.3081 -2.3749)
			(end 1.3081 2.3749)
			(stroke
				(width 0.1524)
				(type default)
			)
			(layer "F.SilkS")
		)
		(fp_line
			(start -1.3081 2.3749)
			(end -1.3081 -2.3749)
			(stroke
				(width 0.1524)
				(type default)
			)
			(layer "F.SilkS")
		)
		(fp_line
			(start -1.3081 -2.3749)
			(end 1.3081 -2.3749)
			(stroke
				(width 0.1524)
				(type default)
			)
			(layer "F.SilkS")
		)
		(fp_rect
			(start -0.8001 1.6002)
			(end 0.8001 -1.6002)
			(stroke
				(width 0)
				(type default)
			)
			(fill no)
			(layer "F.CrtYd")
		)
		(fp_poly
			(pts
				(xy -1.5621 2.4511) (xy -1.5621 1.6002) (xy 0.8001 1.6002) (xy 0.8001 -1.6002) (xy -0.8001 -1.6002)
				(xy -0.8001 1.5875) (xy -1.5621 1.5875) (xy -1.5621 -2.4511) (xy 1.5621 -2.4511) (xy 1.5621 2.4511)
			)
			(stroke
				(width 0)
				(type default)
			)
			(fill no)
			(layer "F.CrtYd")
		)
		(fp_rect
			(start -1.5621 2.4511)
			(end 1.5621 -2.4511)
			(stroke
				(width 0)
				(type default)
			)
			(fill no)
			(layer "F.Fab")
		)
		(pad "1" smd rect
			(at 0 -1.392936 180)
			(size 2.1082 1.4478)
			(layers "F.Cu" "F.Mask" "F.Paste")
			(net "P12V_SSD6")
		)
		(pad "2" smd rect
			(at 0 1.392936 180)
			(size 2.1082 1.4478)
			(layers "F.Cu" "F.Mask" "F.Paste")
			(net "GND")
		)
	)
	(footprint ""
		(layer "F.Cu")
		(at 97.0788 -21.9456 180)
		(property "Reference" "R388"
			(at 0 0 180)
			(layer "F.SilkS")
			(hide yes)
			(effects
				(font
					(size 1.27 1.27)
				)
			)
		)
		(property "Value" "10KR2F-2-GP"
			(at 0.064008 -3.993896 180)
			(unlocked yes)
			(layer "F.Fab")
			(hide yes)
			(effects
				(font
					(size 1.016 1.016)
					(thickness 0.1524)
				)
			)
		)
		(property "Device Type" "R402H16"
			(at 0.064008 -5.517896 180)
			(unlocked yes)
			(layer "F.Fab")
			(hide yes)
			(effects
				(font
					(size 1.016 1.016)
					(thickness 0.1524)
				)
			)
		)
		(duplicate_pad_numbers_are_jumpers no)
		(fp_line
			(start 0.508 -0.9398)
			(end -0.508 -0.9398)
			(stroke
				(width 0.1524)
				(type default)
			)
			(layer "F.SilkS")
		)
		(fp_line
			(start -0.508 -0.9398)
			(end -0.508 0.9398)
			(stroke
				(width 0.1524)
				(type default)
			)
			(layer "F.SilkS")
		)
		(fp_rect
			(start -0.508 0.9398)
			(end 0.508 -0.9398)
			(stroke
				(width 0)
				(type default)
			)
			(fill no)
			(layer "F.CrtYd")
		)
		(fp_rect
			(start -0.508 0.9398)
			(end 0.508 -0.9398)
			(stroke
				(width 0)
				(type default)
			)
			(fill no)
			(layer "F.Fab")
		)
		(pad "1" smd custom
			(at 0 -0.4445 180)
			(size 0.1397 0.1397)
			(layers "F.Cu" "F.Mask" "F.Paste")
			(net "P12V_SSD14")
			(options
				(clearance outline)
				(anchor circle)
			)
			(primitives
				(gr_poly
					(pts
						(arc
							(start -0.1778 -0.2794)
							(mid -0.249642 -0.249642)
							(end -0.2794 -0.1778)
						)
						(arc
							(start -0.2794 0.1778)
							(mid -0.249642 0.249642)
							(end -0.1778 0.2794)
						)
						(arc
							(start 0.1778 0.2794)
							(mid 0.249642 0.249642)
							(end 0.2794 0.1778)
						)
						(arc
							(start 0.2794 -0.1778)
							(mid 0.249642 -0.249642)
							(end 0.1778 -0.2794)
						)
					)
					(width 0)
					(fill yes)
				)
			)
		)
		(pad "2" smd custom
			(at 0 0.4445 180)
			(size 0.1397 0.1397)
			(layers "F.Cu" "F.Mask" "F.Paste")
			(net "P12V_SSD14_SENSE")
			(options
				(clearance outline)
				(anchor circle)
			)
			(primitives
				(gr_poly
					(pts
						(arc
							(start -0.1778 -0.2794)
							(mid -0.249642 -0.249642)
							(end -0.2794 -0.1778)
						)
						(arc
							(start -0.2794 0.1778)
							(mid -0.249642 0.249642)
							(end -0.1778 0.2794)
						)
						(arc
							(start 0.1778 0.2794)
							(mid 0.249642 0.249642)
							(end 0.2794 0.1778)
						)
						(arc
							(start 0.2794 -0.1778)
							(mid 0.249642 -0.249642)
							(end 0.1778 -0.2794)
						)
					)
					(width 0)
					(fill yes)
				)
			)
		)
	)
	(footprint ""
		(layer "F.Cu")
		(at 230.632 -140.19911 -90)
		(property "Reference" "R9803"
			(at 0 0 270)
			(layer "F.SilkS")
			(hide yes)
			(effects
				(font
					(size 1.27 1.27)
				)
			)
		)
		(property "Value" "0R2J-2-GP"
			(at 0.064008 -3.993896 270)
			(unlocked yes)
			(layer "F.Fab")
			(hide yes)
			(effects
				(font
					(size 1.016 1.016)
					(thickness 0.1524)
				)
			)
		)
		(property "Device Type" "R402H16"
			(at 0.064008 -5.517896 270)
			(unlocked yes)
			(layer "F.Fab")
			(hide yes)
			(effects
				(font
					(size 1.016 1.016)
					(thickness 0.1524)
				)
			)
		)
		(duplicate_pad_numbers_are_jumpers no)
		(fp_line
			(start -0.508 -0.9398)
			(end -0.508 0.9398)
			(stroke
				(width 0.1524)
				(type default)
			)
			(layer "F.SilkS")
		)
		(fp_line
			(start 0.508 -0.9398)
			(end -0.508 -0.9398)
			(stroke
				(width 0.1524)
				(type default)
			)
			(layer "F.SilkS")
		)
		(fp_rect
			(start -0.508 0.9398)
			(end 0.508 -0.9398)
			(stroke
				(width 0)
				(type default)
			)
			(fill no)
			(layer "F.CrtYd")
		)
		(fp_rect
			(start -0.508 0.9398)
			(end 0.508 -0.9398)
			(stroke
				(width 0)
				(type default)
			)
			(fill no)
			(layer "F.Fab")
		)
		(pad "1" smd custom
			(at 0 -0.4445 270)
			(size 0.1397 0.1397)
			(layers "F.Cu" "F.Mask" "F.Paste")
			(net "SSD_ACT_DR3_R")
			(options
				(clearance outline)
				(anchor circle)
			)
			(primitives
				(gr_poly
					(pts
						(arc
							(start -0.1778 -0.2794)
							(mid -0.249642 -0.249642)
							(end -0.2794 -0.1778)
						)
						(arc
							(start -0.2794 0.1778)
							(mid -0.249642 0.249642)
							(end -0.1778 0.2794)
						)
						(arc
							(start 0.1778 0.2794)
							(mid 0.249642 0.249642)
							(end 0.2794 0.1778)
						)
						(arc
							(start 0.2794 -0.1778)
							(mid 0.249642 -0.249642)
							(end 0.1778 -0.2794)
						)
					)
					(width 0)
					(fill yes)
				)
			)
		)
		(pad "2" smd custom
			(at 0 0.4445 270)
			(size 0.1397 0.1397)
			(layers "F.Cu" "F.Mask" "F.Paste")
			(net "SSD_ACT_DR3")
			(options
				(clearance outline)
				(anchor circle)
			)
			(primitives
				(gr_poly
					(pts
						(arc
							(start -0.1778 -0.2794)
							(mid -0.249642 -0.249642)
							(end -0.2794 -0.1778)
						)
						(arc
							(start -0.2794 0.1778)
							(mid -0.249642 0.249642)
							(end -0.1778 0.2794)
						)
						(arc
							(start 0.1778 0.2794)
							(mid 0.249642 0.249642)
							(end 0.2794 0.1778)
						)
						(arc
							(start 0.2794 -0.1778)
							(mid 0.249642 -0.249642)
							(end 0.1778 -0.2794)
						)
					)
					(width 0)
					(fill yes)
				)
			)
		)
	)
	(footprint ""
		(layer "F.Cu")
		(at 24.003 -155.194 -90)
		(property "Reference" "R9422"
			(at 0 0 270)
			(layer "F.SilkS")
			(hide yes)
			(effects
				(font
					(size 1.27 1.27)
				)
			)
		)
		(property "Value" "100R2J-2-GP"
			(at 0.064008 -3.993896 270)
			(unlocked yes)
			(layer "F.Fab")
			(hide yes)
			(effects
				(font
					(size 1.016 1.016)
					(thickness 0.1524)
				)
			)
		)
		(property "Device Type" "R402H14"
			(at 0.064008 -5.517896 270)
			(unlocked yes)
			(layer "F.Fab")
			(hide yes)
			(effects
				(font
					(size 1.016 1.016)
					(thickness 0.1524)
				)
			)
		)
		(duplicate_pad_numbers_are_jumpers no)
		(fp_line
			(start -0.508 -0.9398)
			(end -0.508 0.9398)
			(stroke
				(width 0.1524)
				(type default)
			)
			(layer "F.SilkS")
		)
		(fp_line
			(start 0.508 -0.9398)
			(end -0.508 -0.9398)
			(stroke
				(width 0.1524)
				(type default)
			)
			(layer "F.SilkS")
		)
		(fp_rect
			(start -0.508 0.9398)
			(end 0.508 -0.9398)
			(stroke
				(width 0)
				(type default)
			)
			(fill no)
			(layer "F.CrtYd")
		)
		(fp_rect
			(start -0.508 0.9398)
			(end 0.508 -0.9398)
			(stroke
				(width 0)
				(type default)
			)
			(fill no)
			(layer "F.Fab")
		)
		(pad "1" smd custom
			(at 0 -0.4445 270)
			(size 0.1397 0.1397)
			(layers "F.Cu" "F.Mask" "F.Paste")
			(net "P3V3")
			(options
				(clearance outline)
				(anchor circle)
			)
			(primitives
				(gr_poly
					(pts
						(arc
							(start -0.1778 -0.2794)
							(mid -0.249642 -0.249642)
							(end -0.2794 -0.1778)
						)
						(arc
							(start -0.2794 0.1778)
							(mid -0.249642 0.249642)
							(end -0.1778 0.2794)
						)
						(arc
							(start 0.1778 0.2794)
							(mid 0.249642 0.249642)
							(end 0.2794 0.1778)
						)
						(arc
							(start 0.2794 -0.1778)
							(mid 0.249642 -0.249642)
							(end 0.1778 -0.2794)
						)
					)
					(width 0)
					(fill yes)
				)
			)
		)
		(pad "2" smd custom
			(at 0 0.4445 270)
			(size 0.1397 0.1397)
			(layers "F.Cu" "F.Mask" "F.Paste")
			(net "DRV_ACT_13")
			(options
				(clearance outline)
				(anchor circle)
			)
			(primitives
				(gr_poly
					(pts
						(arc
							(start -0.1778 -0.2794)
							(mid -0.249642 -0.249642)
							(end -0.2794 -0.1778)
						)
						(arc
							(start -0.2794 0.1778)
							(mid -0.249642 0.249642)
							(end -0.1778 0.2794)
						)
						(arc
							(start 0.1778 0.2794)
							(mid 0.249642 0.249642)
							(end 0.2794 0.1778)
						)
						(arc
							(start 0.2794 -0.1778)
							(mid 0.249642 -0.249642)
							(end 0.1778 -0.2794)
						)
					)
					(width 0)
					(fill yes)
				)
			)
		)
	)
	(footprint ""
		(layer "F.Cu")
		(at 84.455 -299.339 90)
		(property "Reference" "R9092"
			(at 0 0 90)
			(layer "F.SilkS")
			(hide yes)
			(effects
				(font
					(size 1.27 1.27)
				)
			)
		)
		(property "Value" "4K7R2F-GP"
			(at 0.064008 -3.993896 90)
			(unlocked yes)
			(layer "F.Fab")
			(hide yes)
			(effects
				(font
					(size 1.016 1.016)
					(thickness 0.1524)
				)
			)
		)
		(property "Device Type" "R402H16"
			(at 0.064008 -5.517896 90)
			(unlocked yes)
			(layer "F.Fab")
			(hide yes)
			(effects
				(font
					(size 1.016 1.016)
					(thickness 0.1524)
				)
			)
		)
		(duplicate_pad_numbers_are_jumpers no)
		(fp_line
			(start 0.508 -0.9398)
			(end -0.508 -0.9398)
			(stroke
				(width 0.1524)
				(type default)
			)
			(layer "F.SilkS")
		)
		(fp_line
			(start -0.508 -0.9398)
			(end -0.508 0.9398)
			(stroke
				(width 0.1524)
				(type default)
			)
			(layer "F.SilkS")
		)
		(fp_rect
			(start -0.508 0.9398)
			(end 0.508 -0.9398)
			(stroke
				(width 0)
				(type default)
			)
			(fill no)
			(layer "F.CrtYd")
		)
		(fp_rect
			(start -0.508 0.9398)
			(end 0.508 -0.9398)
			(stroke
				(width 0)
				(type default)
			)
			(fill no)
			(layer "F.Fab")
		)
		(pad "1" smd custom
			(at 0 -0.4445 90)
			(size 0.1397 0.1397)
			(layers "F.Cu" "F.Mask" "F.Paste")
			(net "VDD_DIFF_2")
			(options
				(clearance outline)
				(anchor circle)
			)
			(primitives
				(gr_poly
					(pts
						(arc
							(start -0.1778 -0.2794)
							(mid -0.249642 -0.249642)
							(end -0.2794 -0.1778)
						)
						(arc
							(start -0.2794 0.1778)
							(mid -0.249642 0.249642)
							(end -0.1778 0.2794)
						)
						(arc
							(start 0.1778 0.2794)
							(mid 0.249642 0.249642)
							(end 0.2794 0.1778)
						)
						(arc
							(start 0.2794 -0.1778)
							(mid 0.249642 -0.249642)
							(end 0.1778 -0.2794)
						)
					)
					(width 0)
					(fill yes)
				)
			)
		)
		(pad "2" smd custom
			(at 0 0.4445 90)
			(size 0.1397 0.1397)
			(layers "F.Cu" "F.Mask" "F.Paste")
			(net "CLK_BUF_EU2_SMB_A1_TRI")
			(options
				(clearance outline)
				(anchor circle)
			)
			(primitives
				(gr_poly
					(pts
						(arc
							(start -0.1778 -0.2794)
							(mid -0.249642 -0.249642)
							(end -0.2794 -0.1778)
						)
						(arc
							(start -0.2794 0.1778)
							(mid -0.249642 0.249642)
							(end -0.1778 0.2794)
						)
						(arc
							(start 0.1778 0.2794)
							(mid 0.249642 0.249642)
							(end 0.2794 0.1778)
						)
						(arc
							(start 0.2794 -0.1778)
							(mid 0.249642 -0.249642)
							(end 0.1778 -0.2794)
						)
					)
					(width 0)
					(fill yes)
				)
			)
		)
	)
	(footprint ""
		(layer "F.Cu")
		(at 90.297 -219.456 180)
		(property "Reference" "R9080"
			(at 0 0 180)
			(layer "F.SilkS")
			(hide yes)
			(effects
				(font
					(size 1.27 1.27)
				)
			)
		)
		(property "Value" "27R2F-GP"
			(at 0.064008 -3.993896 180)
			(unlocked yes)
			(layer "F.Fab")
			(hide yes)
			(effects
				(font
					(size 1.016 1.016)
					(thickness 0.1524)
				)
			)
		)
		(property "Device Type" "R402H16"
			(at 0.064008 -5.517896 180)
			(unlocked yes)
			(layer "F.Fab")
			(hide yes)
			(effects
				(font
					(size 1.016 1.016)
					(thickness 0.1524)
				)
			)
		)
		(duplicate_pad_numbers_are_jumpers no)
		(fp_line
			(start 0.508 -0.9398)
			(end -0.508 -0.9398)
			(stroke
				(width 0.1524)
				(type default)
			)
			(layer "F.SilkS")
		)
		(fp_line
			(start -0.508 -0.9398)
			(end -0.508 0.9398)
			(stroke
				(width 0.1524)
				(type default)
			)
			(layer "F.SilkS")
		)
		(fp_rect
			(start -0.508 0.9398)
			(end 0.508 -0.9398)
			(stroke
				(width 0)
				(type default)
			)
			(fill no)
			(layer "F.CrtYd")
		)
		(fp_rect
			(start -0.508 0.9398)
			(end 0.508 -0.9398)
			(stroke
				(width 0)
				(type default)
			)
			(fill no)
			(layer "F.Fab")
		)
		(pad "1" smd custom
			(at 0 -0.4445 180)
			(size 0.1397 0.1397)
			(layers "F.Cu" "F.Mask" "F.Paste")
			(net "PE_CLK_100M_DR12_2_R_N")
			(options
				(clearance outline)
				(anchor circle)
			)
			(primitives
				(gr_poly
					(pts
						(arc
							(start -0.1778 -0.2794)
							(mid -0.249642 -0.249642)
							(end -0.2794 -0.1778)
						)
						(arc
							(start -0.2794 0.1778)
							(mid -0.249642 0.249642)
							(end -0.1778 0.2794)
						)
						(arc
							(start 0.1778 0.2794)
							(mid 0.249642 0.249642)
							(end 0.2794 0.1778)
						)
						(arc
							(start 0.2794 -0.1778)
							(mid 0.249642 -0.249642)
							(end 0.1778 -0.2794)
						)
					)
					(width 0)
					(fill yes)
				)
			)
		)
		(pad "2" smd custom
			(at 0 0.4445 180)
			(size 0.1397 0.1397)
			(layers "F.Cu" "F.Mask" "F.Paste")
			(net "PE_CLK100M_DR12_2_N")
			(options
				(clearance outline)
				(anchor circle)
			)
			(primitives
				(gr_poly
					(pts
						(arc
							(start -0.1778 -0.2794)
							(mid -0.249642 -0.249642)
							(end -0.2794 -0.1778)
						)
						(arc
							(start -0.2794 0.1778)
							(mid -0.249642 0.249642)
							(end -0.1778 0.2794)
						)
						(arc
							(start 0.1778 0.2794)
							(mid 0.249642 0.249642)
							(end 0.2794 0.1778)
						)
						(arc
							(start 0.2794 -0.1778)
							(mid 0.249642 -0.249642)
							(end 0.1778 -0.2794)
						)
					)
					(width 0)
					(fill yes)
				)
			)
		)
	)
)
